(kicad_pcb
	(version 20260206)
	(generator "pcbnew")
	(generator_version "10.0")
	(general
		(thickness 1.6)
		(legacy_teardrops no)
	)
	(paper "A4")
	(title_block
		(title "Bryce Canyon_R.DPB_16317-1_OCP.brd")
		(comment 1 "Bryce Canyon / footprints 1520-1526 of 2099")
	)
	(layers
		(0 "F.Cu" signal "TOP")
		(4 "In1.Cu" signal "L2GND")
		(6 "In2.Cu" signal "L3")
		(8 "In3.Cu" signal "L4VCC")
		(10 "In4.Cu" signal "L5VCC")
		(12 "In5.Cu" signal "L6")
		(14 "In6.Cu" signal "L7GND")
		(2 "B.Cu" signal "BOTTOM")
		(9 "F.Adhes" user "F.Adhesive")
		(11 "B.Adhes" user "B.Adhesive")
		(13 "F.Paste" user "Package Geometry/Pastemask Top")
		(15 "B.Paste" user "Package Geometry/Pastemask Bottom")
		(5 "F.SilkS" user "Ref Des/Silkscreen Top")
		(7 "B.SilkS" user "Ref Des/Silkscreen Bottom")
		(1 "F.Mask" user "Board Geometry/Soldermask Top")
		(3 "B.Mask" user "Board Geometry/Soldermask Bottom")
		(17 "Dwgs.User" user "User.Drawings")
		(19 "Cmts.User" user "User.Comments")
		(21 "Eco1.User" user "User.Eco1")
		(23 "Eco2.User" user "User.Eco2")
		(25 "Edge.Cuts" user "Board Geometry/Outline")
		(27 "Margin" user)
		(31 "F.CrtYd" user "Package Geometry/Place Bound Top")
		(29 "B.CrtYd" user "Package Geometry/Place Bound Bottom")
		(35 "F.Fab" user "Ref Des/Assembly Top")
		(33 "B.Fab" user "Ref Des/Assembly Bottom")
	)
	(footprint ""
		(layer "F.Cu")
		(at 301.371 -228.473 -90)
		(property "Reference" "R4"
			(at 0 0 270)
			(layer "F.SilkS")
			(hide yes)
			(effects
				(font
					(size 1.27 1.27)
				)
			)
		)
		(property "Value" "10KR2F-2-GP"
			(at 0.064008 -3.993896 270)
			(unlocked yes)
			(layer "F.Fab")
			(hide yes)
			(effects
				(font
					(size 1.016 1.016)
					(thickness 0.1524)
				)
			)
		)
		(property "Device Type" "R402H16"
			(at 0.064008 -5.517896 270)
			(unlocked yes)
			(layer "F.Fab")
			(hide yes)
			(effects
				(font
					(size 1.016 1.016)
					(thickness 0.1524)
				)
			)
		)
		(duplicate_pad_numbers_are_jumpers no)
		(fp_line
			(start -0.508 -0.9398)
			(end -0.508 0.9398)
			(stroke
				(width 0.1524)
				(type default)
			)
			(layer "F.SilkS")
		)
		(fp_line
			(start 0.508 -0.9398)
			(end -0.508 -0.9398)
			(stroke
				(width 0.1524)
				(type default)
			)
			(layer "F.SilkS")
		)
		(fp_rect
			(start -0.508 0.9398)
			(end 0.508 -0.9398)
			(stroke
				(width 0)
				(type default)
			)
			(fill no)
			(layer "F.CrtYd")
		)
		(fp_rect
			(start -0.508 0.9398)
			(end 0.508 -0.9398)
			(stroke
				(width 0)
				(type default)
			)
			(fill no)
			(layer "F.Fab")
		)
		(pad "1" smd custom
			(at 0 -0.4445 270)
			(size 0.1397 0.1397)
			(layers "F.Cu" "F.Mask" "F.Paste")
			(net "P3V3_STBY_B")
			(options
				(clearance outline)
				(anchor circle)
			)
			(primitives
				(gr_poly
					(pts
						(arc
							(start -0.1778 -0.2794)
							(mid -0.249642 -0.249642)
							(end -0.2794 -0.1778)
						)
						(arc
							(start -0.2794 0.1778)
							(mid -0.249642 0.249642)
							(end -0.1778 0.2794)
						)
						(arc
							(start 0.1778 0.2794)
							(mid 0.249642 0.249642)
							(end 0.2794 0.1778)
						)
						(arc
							(start 0.2794 -0.1778)
							(mid 0.249642 -0.249642)
							(end 0.1778 -0.2794)
						)
					)
					(width 0)
					(fill yes)
				)
			)
		)
		(pad "2" smd custom
			(at 0 0.4445 270)
			(size 0.1397 0.1397)
			(layers "F.Cu" "F.Mask" "F.Paste")
			(net "SCC_B_TYPE_0")
			(options
				(clearance outline)
				(anchor circle)
			)
			(primitives
				(gr_poly
					(pts
						(arc
							(start -0.1778 -0.2794)
							(mid -0.249642 -0.249642)
							(end -0.2794 -0.1778)
						)
						(arc
							(start -0.2794 0.1778)
							(mid -0.249642 0.249642)
							(end -0.1778 0.2794)
						)
						(arc
							(start 0.1778 0.2794)
							(mid 0.249642 0.249642)
							(end 0.2794 0.1778)
						)
						(arc
							(start 0.2794 -0.1778)
							(mid 0.249642 -0.249642)
							(end 0.1778 -0.2794)
						)
					)
					(width 0)
					(fill yes)
				)
			)
		)
	)
	(footprint ""
		(layer "F.Cu")
		(at 431.419 -148.082)
		(property "Reference" "Q102"
			(at 0 0 0)
			(layer "F.SilkS")
			(hide yes)
			(effects
				(font
					(size 1.27 1.27)
				)
			)
		)
		(property "Value" "AO4407AL-GP"
			(at -3.707384 -1.5367 0)
			(unlocked yes)
			(layer "F.Fab")
			(hide yes)
			(effects
				(font
					(size 1.016 1.016)
					(thickness 0.1524)
				)
			)
		)
		(property "Device Type" "SOIC8H69"
			(at -3.707384 -3.0607 0)
			(unlocked yes)
			(layer "F.Fab")
			(hide yes)
			(effects
				(font
					(size 1.016 1.016)
					(thickness 0.1524)
				)
			)
		)
		(duplicate_pad_numbers_are_jumpers no)
		(fp_line
			(start -2.7432 -1.4224)
			(end -2.7432 1.4224)
			(stroke
				(width 0.1524)
				(type default)
			)
			(layer "F.SilkS")
		)
		(fp_line
			(start -2.7432 1.4224)
			(end -2.6416 1.4224)
			(stroke
				(width 0.1524)
				(type default)
			)
			(layer "F.SilkS")
		)
		(fp_line
			(start -2.7432 1.4224)
			(end 2.1336 1.4224)
			(stroke
				(width 0.1524)
				(type default)
			)
			(layer "F.SilkS")
		)
		(fp_line
			(start -2.7178 -0.508)
			(end -2.1844 -0.0508)
			(stroke
				(width 0.1524)
				(type default)
			)
			(layer "F.SilkS")
		)
		(fp_line
			(start -2.6289 3.4417)
			(end -2.6289 1.4732)
			(stroke
				(width 0.381)
				(type default)
			)
			(layer "F.SilkS")
		)
		(fp_line
			(start -2.1844 -0.0508)
			(end -2.7178 0.508)
			(stroke
				(width 0.1524)
				(type default)
			)
			(layer "F.SilkS")
		)
		(fp_line
			(start 2.1336 -1.4224)
			(end -2.7432 -1.4224)
			(stroke
				(width 0.1524)
				(type default)
			)
			(layer "F.SilkS")
		)
		(fp_line
			(start 2.1336 1.4224)
			(end 2.1336 -1.4224)
			(stroke
				(width 0.1524)
				(type default)
			)
			(layer "F.SilkS")
		)
		(fp_poly
			(pts
				(xy -2.2098 -1.4224) (xy -2.2098 1.4224) (xy 2.2098 1.4224) (xy 2.2098 -1.4224)
			)
			(stroke
				(width 0)
				(type default)
			)
			(fill yes)
			(layer "F.SilkS")
		)
		(fp_rect
			(start -2.450084 2.999994)
			(end 2.450084 -2.999994)
			(stroke
				(width 0)
				(type default)
			)
			(fill no)
			(layer "F.CrtYd")
		)
		(fp_poly
			(pts
				(xy -2.8194 3.6322) (xy -2.8194 -3.6322) (xy 2.8194 -3.6322) (xy 2.8194 1.18364) (xy 2.450084 1.18364)
				(xy 2.450084 -2.999994) (xy -2.450084 -2.999994) (xy -2.450084 2.999994) (xy 2.450084 2.999994)
				(xy 2.450084 1.18618) (xy 2.8194 1.18618) (xy 2.8194 3.6322)
			)
			(stroke
				(width 0)
				(type default)
			)
			(fill no)
			(layer "F.CrtYd")
		)
		(fp_rect
			(start -2.8194 3.6322)
			(end 2.8194 -3.6322)
			(stroke
				(width 0)
				(type default)
			)
			(fill no)
			(layer "F.Fab")
		)
		(pad "1" smd rect
			(at -1.905 2.54)
			(size 0.635 1.651)
			(layers "F.Cu" "F.Mask" "F.Paste")
			(net "P12V_B")
		)
		(pad "2" smd rect
			(at -0.635 2.54)
			(size 0.635 1.651)
			(layers "F.Cu" "F.Mask" "F.Paste")
			(net "P12V_B")
		)
		(pad "3" smd rect
			(at 0.635 2.54)
			(size 0.635 1.651)
			(layers "F.Cu" "F.Mask" "F.Paste")
			(net "P12V_B")
		)
		(pad "4" smd rect
			(at 1.905 2.54)
			(size 0.635 1.651)
			(layers "F.Cu" "F.Mask" "F.Paste")
			(net "SW_HDD_N21")
		)
		(pad "5" smd rect
			(at 1.905 -2.54)
			(size 0.635 1.651)
			(layers "F.Cu" "F.Mask" "F.Paste")
			(net "P12V_HDD21")
		)
		(pad "6" smd rect
			(at 0.635 -2.54)
			(size 0.635 1.651)
			(layers "F.Cu" "F.Mask" "F.Paste")
			(net "P12V_HDD21")
		)
		(pad "7" smd rect
			(at -0.635 -2.54)
			(size 0.635 1.651)
			(layers "F.Cu" "F.Mask" "F.Paste")
			(net "P12V_HDD21")
		)
		(pad "8" smd rect
			(at -1.905 -2.54)
			(size 0.635 1.651)
			(layers "F.Cu" "F.Mask" "F.Paste")
			(net "P12V_HDD21")
		)
	)
	(footprint ""
		(layer "F.Cu")
		(at 234.38104 -233.01198)
		(property "Reference" "R64"
			(at 0 0 0)
			(layer "F.SilkS")
			(hide yes)
			(effects
				(font
					(size 1.27 1.27)
				)
			)
		)
		(property "Value" "4K7R2F-GP"
			(at 0.064008 -3.993896 0)
			(unlocked yes)
			(layer "F.Fab")
			(hide yes)
			(effects
				(font
					(size 1.016 1.016)
					(thickness 0.1524)
				)
			)
		)
		(property "Device Type" "R402H16"
			(at 0.064008 -5.517896 0)
			(unlocked yes)
			(layer "F.Fab")
			(hide yes)
			(effects
				(font
					(size 1.016 1.016)
					(thickness 0.1524)
				)
			)
		)
		(duplicate_pad_numbers_are_jumpers no)
		(fp_line
			(start -0.508 -0.9398)
			(end -0.508 0.9398)
			(stroke
				(width 0.1524)
				(type default)
			)
			(layer "F.SilkS")
		)
		(fp_line
			(start 0.508 -0.9398)
			(end -0.508 -0.9398)
			(stroke
				(width 0.1524)
				(type default)
			)
			(layer "F.SilkS")
		)
		(fp_rect
			(start -0.508 0.9398)
			(end 0.508 -0.9398)
			(stroke
				(width 0)
				(type default)
			)
			(fill no)
			(layer "F.CrtYd")
		)
		(fp_rect
			(start -0.508 0.9398)
			(end 0.508 -0.9398)
			(stroke
				(width 0)
				(type default)
			)
			(fill no)
			(layer "F.Fab")
		)
		(pad "1" smd custom
			(at 0 -0.4445)
			(size 0.1397 0.1397)
			(layers "F.Cu" "F.Mask" "F.Paste")
			(net "P3V3_STBY_B")
			(options
				(clearance outline)
				(anchor circle)
			)
			(primitives
				(gr_poly
					(pts
						(arc
							(start -0.1778 -0.2794)
							(mid -0.249642 -0.249642)
							(end -0.2794 -0.1778)
						)
						(arc
							(start -0.2794 0.1778)
							(mid -0.249642 0.249642)
							(end -0.1778 0.2794)
						)
						(arc
							(start 0.1778 0.2794)
							(mid 0.249642 0.249642)
							(end 0.2794 0.1778)
						)
						(arc
							(start 0.2794 -0.1778)
							(mid 0.249642 -0.249642)
							(end 0.1778 -0.2794)
						)
					)
					(width 0)
					(fill yes)
				)
			)
		)
		(pad "2" smd custom
			(at 0 0.4445)
			(size 0.1397 0.1397)
			(layers "F.Cu" "F.Mask" "F.Paste")
			(net "IO_EXP1_A1")
			(options
				(clearance outline)
				(anchor circle)
			)
			(primitives
				(gr_poly
					(pts
						(arc
							(start -0.1778 -0.2794)
							(mid -0.249642 -0.249642)
							(end -0.2794 -0.1778)
						)
						(arc
							(start -0.2794 0.1778)
							(mid -0.249642 0.249642)
							(end -0.1778 0.2794)
						)
						(arc
							(start 0.1778 0.2794)
							(mid 0.249642 0.249642)
							(end 0.2794 0.1778)
						)
						(arc
							(start 0.2794 -0.1778)
							(mid 0.249642 -0.249642)
							(end 0.1778 -0.2794)
						)
					)
					(width 0)
					(fill yes)
				)
			)
		)
	)
	(footprint ""
		(layer "F.Cu")
		(at 384.734562 -15.219426 -90)
		(property "Reference" "C444"
			(at 0 0 270)
			(layer "F.SilkS")
			(hide yes)
			(effects
				(font
					(size 1.27 1.27)
				)
			)
		)
		(property "Value" "SCD01U16V1KX-GP"
			(at -2.8321 -1.7399 270)
			(unlocked yes)
			(layer "F.Fab")
			(hide yes)
			(effects
				(font
					(size 1.016 1.016)
					(thickness 0.1524)
				)
			)
		)
		(property "Device Type" "C0201H13"
			(at -2.8321 -3.2639 270)
			(unlocked yes)
			(layer "F.Fab")
			(hide yes)
			(effects
				(font
					(size 1.016 1.016)
					(thickness 0.1524)
				)
			)
		)
		(duplicate_pad_numbers_are_jumpers no)
		(fp_rect
			(start -0.2794 0.6477)
			(end 0.2794 -0.6477)
			(stroke
				(width 0)
				(type default)
			)
			(fill no)
			(layer "F.CrtYd")
		)
		(fp_rect
			(start -0.2794 0.6477)
			(end 0.2794 -0.6477)
			(stroke
				(width 0)
				(type default)
			)
			(fill no)
			(layer "F.Fab")
		)
		(pad "1" smd custom
			(at 0 -0.2794 270)
			(size 0.0762 0.0762)
			(layers "F.Cu" "F.Mask" "F.Paste")
			(net "SAS_HDD_RX_N32")
			(options
				(clearance outline)
				(anchor circle)
			)
			(primitives
				(gr_poly
					(pts
						(arc
							(start 0.1524 -0.127)
							(mid 0.137521 -0.162921)
							(end 0.1016 -0.1778)
						)
						(arc
							(start -0.1016 -0.1778)
							(mid -0.137521 -0.162921)
							(end -0.1524 -0.127)
						)
						(arc
							(start -0.1524 0.127)
							(mid -0.137521 0.162921)
							(end -0.1016 0.1778)
						)
						(arc
							(start 0.1016 0.1778)
							(mid 0.137521 0.162921)
							(end 0.1524 0.127)
						)
					)
					(width 0)
					(fill yes)
				)
			)
		)
		(pad "2" smd custom
			(at 0 0.2794 270)
			(size 0.0762 0.0762)
			(layers "F.Cu" "F.Mask" "F.Paste")
			(net "PHY_SCC_B_TO_DRV_B_32_DN")
			(options
				(clearance outline)
				(anchor circle)
			)
			(primitives
				(gr_poly
					(pts
						(arc
							(start 0.1524 -0.127)
							(mid 0.137521 -0.162921)
							(end 0.1016 -0.1778)
						)
						(arc
							(start -0.1016 -0.1778)
							(mid -0.137521 -0.162921)
							(end -0.1524 -0.127)
						)
						(arc
							(start -0.1524 0.127)
							(mid -0.137521 0.162921)
							(end -0.1016 0.1778)
						)
						(arc
							(start 0.1016 0.1778)
							(mid 0.137521 0.162921)
							(end 0.1524 0.127)
						)
					)
					(width 0)
					(fill yes)
				)
			)
		)
	)
	(footprint ""
		(layer "F.Cu")
		(at 463.042 -131.826 180)
		(property "Reference" "R590"
			(at 0 0 180)
			(layer "F.SilkS")
			(hide yes)
			(effects
				(font
					(size 1.27 1.27)
				)
			)
		)
		(property "Value" "4K7R2J-2-GP"
			(at 0.064008 -3.993896 180)
			(unlocked yes)
			(layer "F.Fab")
			(hide yes)
			(effects
				(font
					(size 1.016 1.016)
					(thickness 0.1524)
				)
			)
		)
		(property "Device Type" "R402H16"
			(at 0.064008 -5.517896 180)
			(unlocked yes)
			(layer "F.Fab")
			(hide yes)
			(effects
				(font
					(size 1.016 1.016)
					(thickness 0.1524)
				)
			)
		)
		(duplicate_pad_numbers_are_jumpers no)
		(fp_line
			(start 0.508 -0.9398)
			(end -0.508 -0.9398)
			(stroke
				(width 0.1524)
				(type default)
			)
			(layer "F.SilkS")
		)
		(fp_line
			(start -0.508 -0.9398)
			(end -0.508 0.9398)
			(stroke
				(width 0.1524)
				(type default)
			)
			(layer "F.SilkS")
		)
		(fp_rect
			(start -0.508 0.9398)
			(end 0.508 -0.9398)
			(stroke
				(width 0)
				(type default)
			)
			(fill no)
			(layer "F.CrtYd")
		)
		(fp_rect
			(start -0.508 0.9398)
			(end 0.508 -0.9398)
			(stroke
				(width 0)
				(type default)
			)
			(fill no)
			(layer "F.Fab")
		)
		(pad "1" smd custom
			(at 0 -0.4445 180)
			(size 0.1397 0.1397)
			(layers "F.Cu" "F.Mask" "F.Paste")
			(net "P12V_B")
			(options
				(clearance outline)
				(anchor circle)
			)
			(primitives
				(gr_poly
					(pts
						(arc
							(start -0.1778 -0.2794)
							(mid -0.249642 -0.249642)
							(end -0.2794 -0.1778)
						)
						(arc
							(start -0.2794 0.1778)
							(mid -0.249642 0.249642)
							(end -0.1778 0.2794)
						)
						(arc
							(start 0.1778 0.2794)
							(mid 0.249642 0.249642)
							(end 0.2794 0.1778)
						)
						(arc
							(start 0.2794 -0.1778)
							(mid 0.249642 -0.249642)
							(end 0.1778 -0.2794)
						)
					)
					(width 0)
					(fill yes)
				)
			)
		)
		(pad "2" smd custom
			(at 0 0.4445 180)
			(size 0.1397 0.1397)
			(layers "F.Cu" "F.Mask" "F.Paste")
			(net "SW_HDD_R22")
			(options
				(clearance outline)
				(anchor circle)
			)
			(primitives
				(gr_poly
					(pts
						(arc
							(start -0.1778 -0.2794)
							(mid -0.249642 -0.249642)
							(end -0.2794 -0.1778)
						)
						(arc
							(start -0.2794 0.1778)
							(mid -0.249642 0.249642)
							(end -0.1778 0.2794)
						)
						(arc
							(start 0.1778 0.2794)
							(mid 0.249642 0.249642)
							(end 0.2794 0.1778)
						)
						(arc
							(start 0.2794 -0.1778)
							(mid 0.249642 -0.249642)
							(end 0.1778 -0.2794)
						)
					)
					(width 0)
					(fill yes)
				)
			)
		)
	)
	(footprint ""
		(layer "F.Cu")
		(at 22.32533 -229.963218 90)
		(property "Reference" "R1108"
			(at 0 0 90)
			(layer "F.SilkS")
			(hide yes)
			(effects
				(font
					(size 1.27 1.27)
				)
			)
		)
		(property "Value" "100KR2F-L1-GP"
			(at 0.064008 -3.993896 90)
			(unlocked yes)
			(layer "F.Fab")
			(hide yes)
			(effects
				(font
					(size 1.016 1.016)
					(thickness 0.1524)
				)
			)
		)
		(property "Device Type" "R402H16"
			(at 0.064008 -5.517896 90)
			(unlocked yes)
			(layer "F.Fab")
			(hide yes)
			(effects
				(font
					(size 1.016 1.016)
					(thickness 0.1524)
				)
			)
		)
		(duplicate_pad_numbers_are_jumpers no)
		(fp_line
			(start 0.508 -0.9398)
			(end -0.508 -0.9398)
			(stroke
				(width 0.1524)
				(type default)
			)
			(layer "F.SilkS")
		)
		(fp_line
			(start -0.508 -0.9398)
			(end -0.508 0.9398)
			(stroke
				(width 0.1524)
				(type default)
			)
			(layer "F.SilkS")
		)
		(fp_rect
			(start -0.508 0.9398)
			(end 0.508 -0.9398)
			(stroke
				(width 0)
				(type default)
			)
			(fill no)
			(layer "F.CrtYd")
		)
		(fp_rect
			(start -0.508 0.9398)
			(end 0.508 -0.9398)
			(stroke
				(width 0)
				(type default)
			)
			(fill no)
			(layer "F.Fab")
		)
		(pad "1" smd custom
			(at 0 -0.4445 90)
			(size 0.1397 0.1397)
			(layers "F.Cu" "F.Mask" "F.Paste")
			(net "AGND_P5V_B_1")
			(options
				(clearance outline)
				(anchor circle)
			)
			(primitives
				(gr_poly
					(pts
						(arc
							(start -0.1778 -0.2794)
							(mid -0.249642 -0.249642)
							(end -0.2794 -0.1778)
						)
						(arc
							(start -0.2794 0.1778)
							(mid -0.249642 0.249642)
							(end -0.1778 0.2794)
						)
						(arc
							(start 0.1778 0.2794)
							(mid 0.249642 0.249642)
							(end 0.2794 0.1778)
						)
						(arc
							(start 0.2794 -0.1778)
							(mid 0.249642 -0.249642)
							(end 0.1778 -0.2794)
						)
					)
					(width 0)
					(fill yes)
				)
			)
		)
		(pad "2" smd custom
			(at 0 0.4445 90)
			(size 0.1397 0.1397)
			(layers "F.Cu" "F.Mask" "F.Paste")
			(net "P5V_B_1_MODE")
			(options
				(clearance outline)
				(anchor circle)
			)
			(primitives
				(gr_poly
					(pts
						(arc
							(start -0.1778 -0.2794)
							(mid -0.249642 -0.249642)
							(end -0.2794 -0.1778)
						)
						(arc
							(start -0.2794 0.1778)
							(mid -0.249642 0.249642)
							(end -0.1778 0.2794)
						)
						(arc
							(start 0.1778 0.2794)
							(mid 0.249642 0.249642)
							(end 0.2794 0.1778)
						)
						(arc
							(start 0.2794 -0.1778)
							(mid 0.249642 -0.249642)
							(end 0.1778 -0.2794)
						)
					)
					(width 0)
					(fill yes)
				)
			)
		)
	)
	(footprint ""
		(layer "F.Cu")
		(at 32.352996 -376.9868 90)
		(property "Reference" "R1297"
			(at 0 0 90)
			(layer "F.SilkS")
			(hide yes)
			(effects
				(font
					(size 1.27 1.27)
				)
			)
		)
		(property "Value" "4K7R2F-GP"
			(at 0.064008 -3.993896 90)
			(unlocked yes)
			(layer "F.Fab")
			(hide yes)
			(effects
				(font
					(size 1.016 1.016)
					(thickness 0.1524)
				)
			)
		)
		(property "Device Type" "R402H16"
			(at 0.064008 -5.517896 90)
			(unlocked yes)
			(layer "F.Fab")
			(hide yes)
			(effects
				(font
					(size 1.016 1.016)
					(thickness 0.1524)
				)
			)
		)
		(duplicate_pad_numbers_are_jumpers no)
		(fp_line
			(start 0.508 -0.9398)
			(end -0.508 -0.9398)
			(stroke
				(width 0.1524)
				(type default)
			)
			(layer "F.SilkS")
		)
		(fp_line
			(start -0.508 -0.9398)
			(end -0.508 0.9398)
			(stroke
				(width 0.1524)
				(type default)
			)
			(layer "F.SilkS")
		)
		(fp_rect
			(start -0.508 0.9398)
			(end 0.508 -0.9398)
			(stroke
				(width 0)
				(type default)
			)
			(fill no)
			(layer "F.CrtYd")
		)
		(fp_rect
			(start -0.508 0.9398)
			(end 0.508 -0.9398)
			(stroke
				(width 0)
				(type default)
			)
			(fill no)
			(layer "F.Fab")
		)
		(pad "1" smd custom
			(at 0 -0.4445 90)
			(size 0.1397 0.1397)
			(layers "F.Cu" "F.Mask" "F.Paste")
			(net "FAN_YELLOW_LED0")
			(options
				(clearance outline)
				(anchor circle)
			)
			(primitives
				(gr_poly
					(pts
						(arc
							(start -0.1778 -0.2794)
							(mid -0.249642 -0.249642)
							(end -0.2794 -0.1778)
						)
						(arc
							(start -0.2794 0.1778)
							(mid -0.249642 0.249642)
							(end -0.1778 0.2794)
						)
						(arc
							(start 0.1778 0.2794)
							(mid 0.249642 0.249642)
							(end 0.2794 0.1778)
						)
						(arc
							(start 0.2794 -0.1778)
							(mid 0.249642 -0.249642)
							(end 0.1778 -0.2794)
						)
					)
					(width 0)
					(fill yes)
				)
			)
		)
		(pad "2" smd custom
			(at 0 0.4445 90)
			(size 0.1397 0.1397)
			(layers "F.Cu" "F.Mask" "F.Paste")
			(net "P12V_IN")
			(options
				(clearance outline)
				(anchor circle)
			)
			(primitives
				(gr_poly
					(pts
						(arc
							(start -0.1778 -0.2794)
							(mid -0.249642 -0.249642)
							(end -0.2794 -0.1778)
						)
						(arc
							(start -0.2794 0.1778)
							(mid -0.249642 0.249642)
							(end -0.1778 0.2794)
						)
						(arc
							(start 0.1778 0.2794)
							(mid 0.249642 0.249642)
							(end 0.2794 0.1778)
						)
						(arc
							(start 0.2794 -0.1778)
							(mid 0.249642 -0.249642)
							(end 0.1778 -0.2794)
						)
					)
					(width 0)
					(fill yes)
				)
			)
		)
	)
)
